(kicad_pcb
	(version 20260206)
	(generator "pcbnew")
	(generator_version "10.0")
	(general
		(thickness 1.6)
		(legacy_teardrops no)
	)
	(paper "A4")
	(title_block
		(title "04192023_DAF0TMB3IC0_F0TG_MB_C_brd_V02_OCP.brd")
		(comment 1 "Grand Teton / footprints 348-356 of 8354")
	)
	(layers
		(0 "F.Cu" signal "TOP")
		(4 "In1.Cu" signal "GND")
		(6 "In2.Cu" signal "IN1")
		(8 "In3.Cu" signal "GND1")
		(10 "In4.Cu" signal "IN2")
		(12 "In5.Cu" signal "GND2")
		(14 "In6.Cu" signal "IN3")
		(16 "In7.Cu" signal "GND3")
		(18 "In8.Cu" signal "VCC")
		(20 "In9.Cu" signal "VCC1")
		(22 "In10.Cu" signal "GND4")
		(24 "In11.Cu" signal "IN4")
		(26 "In12.Cu" signal "GND5")
		(28 "In13.Cu" signal "IN5")
		(30 "In14.Cu" signal "GND6")
		(32 "In15.Cu" signal "IN6")
		(34 "In16.Cu" signal "GND7")
		(2 "B.Cu" signal "BOTTOM")
		(9 "F.Adhes" user "F.Adhesive")
		(11 "B.Adhes" user "B.Adhesive")
		(13 "F.Paste" user "Package Geometry/Pastemask Top")
		(15 "B.Paste" user "Package Geometry/Pastemask Bottom")
		(5 "F.SilkS" user "Ref Des/Silkscreen Top")
		(7 "B.SilkS" user "Ref Des/Silkscreen Bottom")
		(1 "F.Mask" user "Board Geometry/Soldermask Top")
		(3 "B.Mask" user "Board Geometry/Soldermask Bottom")
		(17 "Dwgs.User" user "User.Drawings")
		(19 "Cmts.User" user "User.Comments")
		(21 "Eco1.User" user "User.Eco1")
		(23 "Eco2.User" user "User.Eco2")
		(25 "Edge.Cuts" user "Board Geometry/Outline")
		(27 "Margin" user)
		(31 "F.CrtYd" user "Package Geometry/Place Bound Top")
		(29 "B.CrtYd" user "Package Geometry/Place Bound Bottom")
		(35 "F.Fab" user "Ref Des/Assembly Top")
		(33 "B.Fab" user "Ref Des/Assembly Bottom")
	)
	(footprint ""
		(layer "F.Cu")
		(at 347.98889 -338.200238 90)
		(property "Reference" "PR155"
			(at 0 0 90)
			(layer "F.SilkS")
			(hide yes)
			(effects
				(font
					(size 1.27 1.27)
				)
			)
		)
		(property "Value" ""
			(at 0 0 90)
			(layer "F.Fab")
			(effects
				(font
					(size 1.27 1.27)
				)
			)
		)
		(duplicate_pad_numbers_are_jumpers no)
		(fp_line
			(start 0.7874 -0.4064)
			(end 0.7874 0.4064)
			(stroke
				(width 0.1524)
				(type default)
			)
			(layer "F.SilkS")
		)
		(fp_line
			(start -0.7874 -0.4064)
			(end 0.7874 -0.4064)
			(stroke
				(width 0.1524)
				(type default)
			)
			(layer "F.SilkS")
		)
		(fp_line
			(start 0.7874 0.4064)
			(end -0.7874 0.4064)
			(stroke
				(width 0.1524)
				(type default)
			)
			(layer "F.SilkS")
		)
		(fp_line
			(start -0.7874 0.4064)
			(end -0.7874 -0.4064)
			(stroke
				(width 0.1524)
				(type default)
			)
			(layer "F.SilkS")
		)
		(fp_line
			(start -0.12065 -0.305054)
			(end -0.12065 -0.2794)
			(stroke
				(width 0.1)
				(type default)
			)
			(layer "F.Fab")
		)
		(fp_line
			(start -0.67945 -0.305054)
			(end -0.12065 -0.305054)
			(stroke
				(width 0.1)
				(type default)
			)
			(layer "F.Fab")
		)
		(fp_line
			(start 0.67945 -0.3048)
			(end 0.67945 0.3048)
			(stroke
				(width 0.1)
				(type default)
			)
			(layer "F.Fab")
		)
		(fp_line
			(start 0.12065 -0.3048)
			(end 0.67945 -0.3048)
			(stroke
				(width 0.1)
				(type default)
			)
			(layer "F.Fab")
		)
		(fp_line
			(start 0.12065 -0.2794)
			(end 0.12065 -0.3048)
			(stroke
				(width 0.1)
				(type default)
			)
			(layer "F.Fab")
		)
		(fp_line
			(start -0.12065 -0.2794)
			(end 0.12065 -0.2794)
			(stroke
				(width 0.1)
				(type default)
			)
			(layer "F.Fab")
		)
		(fp_line
			(start 0.120396 0.2794)
			(end -0.12065 0.2794)
			(stroke
				(width 0.1)
				(type default)
			)
			(layer "F.Fab")
		)
		(fp_line
			(start -0.12065 0.2794)
			(end -0.12065 0.3048)
			(stroke
				(width 0.1)
				(type default)
			)
			(layer "F.Fab")
		)
		(fp_line
			(start 0.67945 0.3048)
			(end 0.120396 0.3048)
			(stroke
				(width 0.1)
				(type default)
			)
			(layer "F.Fab")
		)
		(fp_line
			(start 0.120396 0.3048)
			(end 0.120396 0.2794)
			(stroke
				(width 0.1)
				(type default)
			)
			(layer "F.Fab")
		)
		(fp_line
			(start -0.12065 0.3048)
			(end -0.67945 0.3048)
			(stroke
				(width 0.1)
				(type default)
			)
			(layer "F.Fab")
		)
		(fp_line
			(start -0.67945 0.3048)
			(end -0.67945 -0.305054)
			(stroke
				(width 0.1)
				(type default)
			)
			(layer "F.Fab")
		)
		(pad "1" smd circle
			(at -0.40005 0 90)
			(size 0 0)
			(layers "F.Cu" "F.Mask" "F.Paste")
			(net "SW_PVDDCR_CPU1_P0_SW6_RC")
		)
		(pad "2" smd circle
			(at 0.40005 0 90)
			(size 0 0)
			(layers "F.Cu" "F.Mask" "F.Paste")
			(net "GND")
		)
	)
	(footprint ""
		(layer "F.Cu")
		(at 213.54288 -32.857948 180)
		(property "Reference" "R3577"
			(at 0 0 180)
			(layer "F.SilkS")
			(hide yes)
			(effects
				(font
					(size 1.27 1.27)
				)
			)
		)
		(property "Value" ""
			(at 0 0 180)
			(layer "F.Fab")
			(effects
				(font
					(size 1.27 1.27)
				)
			)
		)
		(duplicate_pad_numbers_are_jumpers no)
		(fp_line
			(start 0.7874 0.4064)
			(end -0.7874 0.4064)
			(stroke
				(width 0.1524)
				(type default)
			)
			(layer "F.SilkS")
		)
		(fp_line
			(start 0.7874 -0.4064)
			(end 0.7874 0.4064)
			(stroke
				(width 0.1524)
				(type default)
			)
			(layer "F.SilkS")
		)
		(fp_line
			(start -0.7874 0.4064)
			(end -0.7874 -0.4064)
			(stroke
				(width 0.1524)
				(type default)
			)
			(layer "F.SilkS")
		)
		(fp_line
			(start -0.7874 -0.4064)
			(end 0.7874 -0.4064)
			(stroke
				(width 0.1524)
				(type default)
			)
			(layer "F.SilkS")
		)
		(fp_line
			(start 0.67945 0.3048)
			(end 0.120396 0.3048)
			(stroke
				(width 0.1)
				(type default)
			)
			(layer "F.Fab")
		)
		(fp_line
			(start 0.67945 -0.3048)
			(end 0.67945 0.3048)
			(stroke
				(width 0.1)
				(type default)
			)
			(layer "F.Fab")
		)
		(fp_line
			(start 0.12065 -0.2794)
			(end 0.12065 -0.3048)
			(stroke
				(width 0.1)
				(type default)
			)
			(layer "F.Fab")
		)
		(fp_line
			(start 0.12065 -0.3048)
			(end 0.67945 -0.3048)
			(stroke
				(width 0.1)
				(type default)
			)
			(layer "F.Fab")
		)
		(fp_line
			(start 0.120396 0.3048)
			(end 0.120396 0.2794)
			(stroke
				(width 0.1)
				(type default)
			)
			(layer "F.Fab")
		)
		(fp_line
			(start 0.120396 0.2794)
			(end -0.12065 0.2794)
			(stroke
				(width 0.1)
				(type default)
			)
			(layer "F.Fab")
		)
		(fp_line
			(start -0.12065 0.3048)
			(end -0.67945 0.3048)
			(stroke
				(width 0.1)
				(type default)
			)
			(layer "F.Fab")
		)
		(fp_line
			(start -0.12065 0.2794)
			(end -0.12065 0.3048)
			(stroke
				(width 0.1)
				(type default)
			)
			(layer "F.Fab")
		)
		(fp_line
			(start -0.12065 -0.2794)
			(end 0.12065 -0.2794)
			(stroke
				(width 0.1)
				(type default)
			)
			(layer "F.Fab")
		)
		(fp_line
			(start -0.12065 -0.305054)
			(end -0.12065 -0.2794)
			(stroke
				(width 0.1)
				(type default)
			)
			(layer "F.Fab")
		)
		(fp_line
			(start -0.67945 0.3048)
			(end -0.67945 -0.305054)
			(stroke
				(width 0.1)
				(type default)
			)
			(layer "F.Fab")
		)
		(fp_line
			(start -0.67945 -0.305054)
			(end -0.12065 -0.305054)
			(stroke
				(width 0.1)
				(type default)
			)
			(layer "F.Fab")
		)
		(pad "1" smd circle
			(at -0.40005 0 180)
			(size 0 0)
			(layers "F.Cu" "F.Mask" "F.Paste")
			(net "SMB_INA230_5_3V3AUX_SDA_R")
		)
		(pad "2" smd circle
			(at 0.40005 0 180)
			(size 0 0)
			(layers "F.Cu" "F.Mask" "F.Paste")
			(net "SMB_INA230_5_3V3AUX_SDA_R1")
		)
	)
	(footprint ""
		(layer "F.Cu")
		(at 399.350484 -403.285452 90)
		(property "Reference" "R1054"
			(at 0 0 90)
			(layer "F.SilkS")
			(hide yes)
			(effects
				(font
					(size 1.27 1.27)
				)
			)
		)
		(property "Value" ""
			(at 0 0 90)
			(layer "F.Fab")
			(effects
				(font
					(size 1.27 1.27)
				)
			)
		)
		(duplicate_pad_numbers_are_jumpers no)
		(fp_line
			(start 0.32512 -0.175006)
			(end 0.32512 0.175006)
			(stroke
				(width 0.1)
				(type default)
			)
			(layer "F.Fab")
		)
		(fp_line
			(start -0.32512 -0.175006)
			(end 0.32512 -0.175006)
			(stroke
				(width 0.1)
				(type default)
			)
			(layer "F.Fab")
		)
		(fp_line
			(start 0.32512 0.175006)
			(end -0.32512 0.175006)
			(stroke
				(width 0.1)
				(type default)
			)
			(layer "F.Fab")
		)
		(fp_line
			(start -0.32512 0.175006)
			(end -0.32512 -0.175006)
			(stroke
				(width 0.1)
				(type default)
			)
			(layer "F.Fab")
		)
		(pad "1" smd rect
			(at -0.2667 0 90)
			(size 0.3048 0.381)
			(layers "F.Cu" "F.Mask" "F.Paste")
			(net "RST_RT_CPU0_P2_RESET_N")
		)
		(pad "2" smd rect
			(at 0.2667 0 270)
			(size 0.3048 0.381)
			(layers "F.Cu" "F.Mask" "F.Paste")
			(net "RST_RT_CPU0_P2_RESET_R_N")
		)
	)
	(footprint ""
		(layer "F.Cu")
		(at 204.851 -337.439 -90)
		(property "Reference" "PC128"
			(at 0 0 270)
			(layer "F.SilkS")
			(hide yes)
			(effects
				(font
					(size 1.27 1.27)
				)
			)
		)
		(property "Value" ""
			(at 0 0 270)
			(layer "F.Fab")
			(effects
				(font
					(size 1.27 1.27)
				)
			)
		)
		(duplicate_pad_numbers_are_jumpers no)
		(fp_line
			(start -0.7874 0.4064)
			(end -0.7874 -0.4064)
			(stroke
				(width 0.1524)
				(type default)
			)
			(layer "F.SilkS")
		)
		(fp_line
			(start 0.7874 0.4064)
			(end -0.7874 0.4064)
			(stroke
				(width 0.1524)
				(type default)
			)
			(layer "F.SilkS")
		)
		(fp_line
			(start -0.7874 -0.4064)
			(end 0.7874 -0.4064)
			(stroke
				(width 0.1524)
				(type default)
			)
			(layer "F.SilkS")
		)
		(fp_line
			(start 0.7874 -0.4064)
			(end 0.7874 0.4064)
			(stroke
				(width 0.1524)
				(type default)
			)
			(layer "F.SilkS")
		)
		(fp_line
			(start -0.67945 0.3048)
			(end -0.67945 -0.305054)
			(stroke
				(width 0.1)
				(type default)
			)
			(layer "F.Fab")
		)
		(fp_line
			(start -0.12065 0.3048)
			(end -0.67945 0.3048)
			(stroke
				(width 0.1)
				(type default)
			)
			(layer "F.Fab")
		)
		(fp_line
			(start 0.120396 0.3048)
			(end 0.120396 0.2794)
			(stroke
				(width 0.1)
				(type default)
			)
			(layer "F.Fab")
		)
		(fp_line
			(start 0.67945 0.3048)
			(end 0.120396 0.3048)
			(stroke
				(width 0.1)
				(type default)
			)
			(layer "F.Fab")
		)
		(fp_line
			(start -0.12065 0.2794)
			(end -0.12065 0.3048)
			(stroke
				(width 0.1)
				(type default)
			)
			(layer "F.Fab")
		)
		(fp_line
			(start 0.120396 0.2794)
			(end -0.12065 0.2794)
			(stroke
				(width 0.1)
				(type default)
			)
			(layer "F.Fab")
		)
		(fp_line
			(start -0.12065 -0.2794)
			(end 0.12065 -0.2794)
			(stroke
				(width 0.1)
				(type default)
			)
			(layer "F.Fab")
		)
		(fp_line
			(start 0.12065 -0.2794)
			(end 0.12065 -0.3048)
			(stroke
				(width 0.1)
				(type default)
			)
			(layer "F.Fab")
		)
		(fp_line
			(start 0.12065 -0.3048)
			(end 0.67945 -0.3048)
			(stroke
				(width 0.1)
				(type default)
			)
			(layer "F.Fab")
		)
		(fp_line
			(start 0.67945 -0.3048)
			(end 0.67945 0.3048)
			(stroke
				(width 0.1)
				(type default)
			)
			(layer "F.Fab")
		)
		(fp_line
			(start -0.67945 -0.305054)
			(end -0.12065 -0.305054)
			(stroke
				(width 0.1)
				(type default)
			)
			(layer "F.Fab")
		)
		(fp_line
			(start -0.12065 -0.305054)
			(end -0.12065 -0.2794)
			(stroke
				(width 0.1)
				(type default)
			)
			(layer "F.Fab")
		)
		(pad "1" smd circle
			(at -0.40005 0 270)
			(size 0 0)
			(layers "F.Cu" "F.Mask" "F.Paste")
			(net "SW_PVDD_33_S5_BST_R")
		)
		(pad "2" smd circle
			(at 0.40005 0 270)
			(size 0 0)
			(layers "F.Cu" "F.Mask" "F.Paste")
			(net "SW_PVDD_33_S5_SW")
		)
	)
	(footprint ""
		(layer "F.Cu")
		(at 425.3484 -421.64 90)
		(property "Reference" "R1482"
			(at 0 0 90)
			(layer "F.SilkS")
			(hide yes)
			(effects
				(font
					(size 1.27 1.27)
				)
			)
		)
		(property "Value" ""
			(at 0 0 90)
			(layer "F.Fab")
			(effects
				(font
					(size 1.27 1.27)
				)
			)
		)
		(duplicate_pad_numbers_are_jumpers no)
		(fp_line
			(start 0.32512 -0.175006)
			(end 0.32512 0.175006)
			(stroke
				(width 0.1)
				(type default)
			)
			(layer "F.Fab")
		)
		(fp_line
			(start -0.32512 -0.175006)
			(end 0.32512 -0.175006)
			(stroke
				(width 0.1)
				(type default)
			)
			(layer "F.Fab")
		)
		(fp_line
			(start 0.32512 0.175006)
			(end -0.32512 0.175006)
			(stroke
				(width 0.1)
				(type default)
			)
			(layer "F.Fab")
		)
		(fp_line
			(start -0.32512 0.175006)
			(end -0.32512 -0.175006)
			(stroke
				(width 0.1)
				(type default)
			)
			(layer "F.Fab")
		)
		(pad "1" smd rect
			(at -0.2667 0 90)
			(size 0.3048 0.381)
			(layers "F.Cu" "F.Mask" "F.Paste")
			(net "P1V8_CPU0_RT_1D")
		)
		(pad "2" smd rect
			(at 0.2667 0 270)
			(size 0.3048 0.381)
			(layers "F.Cu" "F.Mask" "F.Paste")
			(net "JTAG_TDI_RT_CPU0_P3")
		)
	)
	(footprint ""
		(layer "F.Cu")
		(at 381.405892 -378.95403 -90)
		(property "Reference" "C883"
			(at 0 0 270)
			(layer "F.SilkS")
			(hide yes)
			(effects
				(font
					(size 1.27 1.27)
				)
			)
		)
		(property "Value" ""
			(at 0 0 270)
			(layer "F.Fab")
			(effects
				(font
					(size 1.27 1.27)
				)
			)
		)
		(duplicate_pad_numbers_are_jumpers no)
		(fp_line
			(start -0.299974 0.150114)
			(end -0.299974 -0.150114)
			(stroke
				(width 0.1)
				(type default)
			)
			(layer "F.Fab")
		)
		(fp_line
			(start 0.299974 0.150114)
			(end -0.299974 0.150114)
			(stroke
				(width 0.1)
				(type default)
			)
			(layer "F.Fab")
		)
		(fp_line
			(start -0.299974 -0.150114)
			(end 0.299974 -0.150114)
			(stroke
				(width 0.1)
				(type default)
			)
			(layer "F.Fab")
		)
		(fp_line
			(start 0.299974 -0.150114)
			(end 0.299974 0.150114)
			(stroke
				(width 0.1)
				(type default)
			)
			(layer "F.Fab")
		)
		(pad "1" smd rect
			(at -0.2667 0 270)
			(size 0.3048 0.381)
			(layers "F.Cu" "F.Mask" "F.Paste")
			(net "P5E_CPU0_P3_TX_C_DP<9>")
		)
		(pad "2" smd rect
			(at 0.2667 0 270)
			(size 0.3048 0.381)
			(layers "F.Cu" "F.Mask" "F.Paste")
			(net "P5E_CPU0_P3_TX_DP<9>")
		)
	)
	(footprint ""
		(layer "F.Cu")
		(at 170.213782 -392.074146)
		(property "Reference" "C398"
			(at 0 0 0)
			(layer "F.SilkS")
			(hide yes)
			(effects
				(font
					(size 1.27 1.27)
				)
			)
		)
		(property "Value" ""
			(at 0 0 0)
			(layer "F.Fab")
			(effects
				(font
					(size 1.27 1.27)
				)
			)
		)
		(duplicate_pad_numbers_are_jumpers no)
		(fp_line
			(start -1.524 -0.762)
			(end 1.524 -0.762)
			(stroke
				(width 0.1524)
				(type default)
			)
			(layer "F.SilkS")
		)
		(fp_line
			(start -1.524 0.762)
			(end -1.524 -0.762)
			(stroke
				(width 0.1524)
				(type default)
			)
			(layer "F.SilkS")
		)
		(fp_line
			(start 1.524 -0.762)
			(end 1.524 0.762)
			(stroke
				(width 0.1524)
				(type default)
			)
			(layer "F.SilkS")
		)
		(fp_line
			(start 1.524 0.762)
			(end -1.524 0.762)
			(stroke
				(width 0.1524)
				(type default)
			)
			(layer "F.SilkS")
		)
		(fp_line
			(start -1.1049 -0.724916)
			(end -1.1049 0.724916)
			(stroke
				(width 0.1)
				(type default)
			)
			(layer "F.Fab")
		)
		(fp_line
			(start -1.1049 0.724916)
			(end 1.1049 0.724916)
			(stroke
				(width 0.1)
				(type default)
			)
			(layer "F.Fab")
		)
		(fp_line
			(start 1.1049 -0.724916)
			(end -1.1049 -0.724916)
			(stroke
				(width 0.1)
				(type default)
			)
			(layer "F.Fab")
		)
		(fp_line
			(start 1.1049 0.724916)
			(end 1.1049 -0.724916)
			(stroke
				(width 0.1)
				(type default)
			)
			(layer "F.Fab")
		)
		(pad "1" smd rect
			(at -0.889 0 180)
			(size 1.016 1.27)
			(layers "F.Cu" "F.Mask" "F.Paste")
			(net "P0V9_CPU1_RT2_2A")
		)
		(pad "2" smd rect
			(at 0.889 0 180)
			(size 1.016 1.27)
			(layers "F.Cu" "F.Mask" "F.Paste")
			(net "GND")
		)
	)
	(footprint ""
		(layer "F.Cu")
		(at 372.937278 -144.520158 180)
		(property "Reference" "R8289"
			(at 0 0 180)
			(layer "F.SilkS")
			(hide yes)
			(effects
				(font
					(size 1.27 1.27)
				)
			)
		)
		(property "Value" ""
			(at 0 0 180)
			(layer "F.Fab")
			(effects
				(font
					(size 1.27 1.27)
				)
			)
		)
		(duplicate_pad_numbers_are_jumpers no)
		(fp_line
			(start 0.7874 0.4064)
			(end -0.7874 0.4064)
			(stroke
				(width 0.1524)
				(type default)
			)
			(layer "F.SilkS")
		)
		(fp_line
			(start 0.7874 -0.4064)
			(end 0.7874 0.4064)
			(stroke
				(width 0.1524)
				(type default)
			)
			(layer "F.SilkS")
		)
		(fp_line
			(start -0.7874 0.4064)
			(end -0.7874 -0.4064)
			(stroke
				(width 0.1524)
				(type default)
			)
			(layer "F.SilkS")
		)
		(fp_line
			(start -0.7874 -0.4064)
			(end 0.7874 -0.4064)
			(stroke
				(width 0.1524)
				(type default)
			)
			(layer "F.SilkS")
		)
		(fp_line
			(start 0.67945 0.3048)
			(end 0.120396 0.3048)
			(stroke
				(width 0.1)
				(type default)
			)
			(layer "F.Fab")
		)
		(fp_line
			(start 0.67945 -0.3048)
			(end 0.67945 0.3048)
			(stroke
				(width 0.1)
				(type default)
			)
			(layer "F.Fab")
		)
		(fp_line
			(start 0.12065 -0.2794)
			(end 0.12065 -0.3048)
			(stroke
				(width 0.1)
				(type default)
			)
			(layer "F.Fab")
		)
		(fp_line
			(start 0.12065 -0.3048)
			(end 0.67945 -0.3048)
			(stroke
				(width 0.1)
				(type default)
			)
			(layer "F.Fab")
		)
		(fp_line
			(start 0.120396 0.3048)
			(end 0.120396 0.2794)
			(stroke
				(width 0.1)
				(type default)
			)
			(layer "F.Fab")
		)
		(fp_line
			(start 0.120396 0.2794)
			(end -0.12065 0.2794)
			(stroke
				(width 0.1)
				(type default)
			)
			(layer "F.Fab")
		)
		(fp_line
			(start -0.12065 0.3048)
			(end -0.67945 0.3048)
			(stroke
				(width 0.1)
				(type default)
			)
			(layer "F.Fab")
		)
		(fp_line
			(start -0.12065 0.2794)
			(end -0.12065 0.3048)
			(stroke
				(width 0.1)
				(type default)
			)
			(layer "F.Fab")
		)
		(fp_line
			(start -0.12065 -0.2794)
			(end 0.12065 -0.2794)
			(stroke
				(width 0.1)
				(type default)
			)
			(layer "F.Fab")
		)
		(fp_line
			(start -0.12065 -0.305054)
			(end -0.12065 -0.2794)
			(stroke
				(width 0.1)
				(type default)
			)
			(layer "F.Fab")
		)
		(fp_line
			(start -0.67945 0.3048)
			(end -0.67945 -0.305054)
			(stroke
				(width 0.1)
				(type default)
			)
			(layer "F.Fab")
		)
		(fp_line
			(start -0.67945 -0.305054)
			(end -0.12065 -0.305054)
			(stroke
				(width 0.1)
				(type default)
			)
			(layer "F.Fab")
		)
		(pad "1" smd circle
			(at -0.40005 0 180)
			(size 0 0)
			(layers "F.Cu" "F.Mask" "F.Paste")
			(net "PVDD18_S5_P0")
		)
		(pad "2" smd circle
			(at 0.40005 0 180)
			(size 0 0)
			(layers "F.Cu" "F.Mask" "F.Paste")
			(net "SVID_PVDDCR_CPU0_P0_SVD_R")
		)
	)
	(footprint ""
		(layer "F.Cu")
		(at 67.062604 -408.517344 -90)
		(property "Reference" "C6641"
			(at 0 0 270)
			(layer "F.SilkS")
			(hide yes)
			(effects
				(font
					(size 1.27 1.27)
				)
			)
		)
		(property "Value" ""
			(at 0 0 270)
			(layer "F.Fab")
			(effects
				(font
					(size 1.27 1.27)
				)
			)
		)
		(duplicate_pad_numbers_are_jumpers no)
		(fp_line
			(start -0.299974 0.150114)
			(end -0.299974 -0.150114)
			(stroke
				(width 0.1)
				(type default)
			)
			(layer "F.Fab")
		)
		(fp_line
			(start 0.299974 0.150114)
			(end -0.299974 0.150114)
			(stroke
				(width 0.1)
				(type default)
			)
			(layer "F.Fab")
		)
		(fp_line
			(start -0.299974 -0.150114)
			(end 0.299974 -0.150114)
			(stroke
				(width 0.1)
				(type default)
			)
			(layer "F.Fab")
		)
		(fp_line
			(start 0.299974 -0.150114)
			(end 0.299974 0.150114)
			(stroke
				(width 0.1)
				(type default)
			)
			(layer "F.Fab")
		)
		(pad "1" smd rect
			(at -0.2667 0 270)
			(size 0.3048 0.381)
			(layers "F.Cu" "F.Mask" "F.Paste")
			(net "P5E_CPU1_P0_TX_BUF_C_DP<6>")
		)
		(pad "2" smd rect
			(at 0.2667 0 270)
			(size 0.3048 0.381)
			(layers "F.Cu" "F.Mask" "F.Paste")
			(net "P5E_CPU1_P0_TX_BUF_DP<6>")
		)
	)
)
